# BASEBOARD_FAB2 (Tioga Pass) — schematic netlist excerpt (pin names and nets, part order shuffled) for the footprints in the layout excerpt that follows; sources: Cadence DE-HDL packaged netlist, KiCad conversion of Wiwynn_Tioga_Pass_MB.brd

R9G24  RES  0.0 5% CHIP  pkg 0402  page 141 : A = NIC_MDI_SPRV_RJ45_0_DP ; B = NIC_MDI_SPRV_RJ45_0_R_DP
R1D35  RES  4.75K 1% CHIP  pkg 0402  page 126 : A = P3V3_STBY ; B = FM_OC_DETECT_EN_N
R1D6  RES  1.00K 1% CHIP  pkg 0402  page 206 : A = P3V3_STBY ; B = IRQ_PVCCIN_CPU1_VRHOT_LVC3_R_N

(kicad_pcb
	(version 20260206)
	(generator "pcbnew")
	(generator_version "10.0")
	(general
		(thickness 1.6)
		(legacy_teardrops no)
	)
	(paper "A4")
	(title_block
		(title "Wiwynn_Tioga_Pass_MB.brd")
		(comment 1 "Tioga Pass / footprints 1254-1256 of 4770")
	)
	(layers
		(0 "F.Cu" signal "TOP")
		(4 "In1.Cu" signal "L2GND")
		(6 "In2.Cu" signal "L3")
		(8 "In3.Cu" signal "L4GND")
		(10 "In4.Cu" signal "L5")
		(12 "In5.Cu" signal "L6GND")
		(14 "In6.Cu" signal "L7VCC")
		(16 "In7.Cu" signal "L8VCC")
		(18 "In8.Cu" signal "L9GND")
		(20 "In9.Cu" signal "L10")
		(22 "In10.Cu" signal "L11GND")
		(24 "In11.Cu" signal "L12")
		(26 "In12.Cu" signal "L13GND")
		(2 "B.Cu" signal "BOTTOM")
		(9 "F.Adhes" user "F.Adhesive")
		(11 "B.Adhes" user "B.Adhesive")
		(13 "F.Paste" user "Package Geometry/Pastemask Top")
		(15 "B.Paste" user "Package Geometry/Pastemask Bottom")
		(5 "F.SilkS" user "Ref Des/Silkscreen Top")
		(7 "B.SilkS" user "Ref Des/Silkscreen Bottom")
		(1 "F.Mask" user "Board Geometry/Soldermask Top")
		(3 "B.Mask" user "Board Geometry/Soldermask Bottom")
		(17 "Dwgs.User" user "User.Drawings")
		(19 "Cmts.User" user "User.Comments")
		(21 "Eco1.User" user "User.Eco1")
		(23 "Eco2.User" user "User.Eco2")
		(25 "Edge.Cuts" user "Board Geometry/Outline")
		(27 "Margin" user)
		(31 "F.CrtYd" user "Package Geometry/Place Bound Top")
		(29 "B.CrtYd" user "Package Geometry/Place Bound Bottom")
		(35 "F.Fab" user "Ref Des/Assembly Top")
		(33 "B.Fab" user "Ref Des/Assembly Bottom")
	)
	(footprint ""
		(layer "F.Cu")
		(at 25.908 -75.819 -90)
		(property "Reference" "R1D35"
			(at 0 0 270)
			(layer "F.SilkS")
			(hide yes)
			(effects
				(font
					(size 1.27 1.27)
				)
			)
		)
		(property "Value" ""
			(at 0 0 270)
			(layer "F.Fab")
			(effects
				(font
					(size 1.27 1.27)
				)
			)
		)
		(duplicate_pad_numbers_are_jumpers no)
		(fp_poly
			(pts
				(xy -0.2794 -0.1016) (xy 0.2794 -0.1016) (xy 0.2794 0.9906) (xy -0.2794 0.9906)
			)
			(stroke
				(width 0)
				(type default)
			)
			(fill no)
			(layer "F.CrtYd")
		)
		(fp_line
			(start -0.2794 0.9906)
			(end 0.2794 0.9906)
			(stroke
				(width 0.1)
				(type default)
			)
			(layer "F.Fab")
		)
		(fp_line
			(start 0.2794 0.9906)
			(end 0.2794 -0.1016)
			(stroke
				(width 0.1)
				(type default)
			)
			(layer "F.Fab")
		)
		(fp_line
			(start -0.2794 -0.1016)
			(end -0.2794 0.9906)
			(stroke
				(width 0.1)
				(type default)
			)
			(layer "F.Fab")
		)
		(fp_line
			(start 0.2794 -0.1016)
			(end -0.2794 -0.1016)
			(stroke
				(width 0.1)
				(type default)
			)
			(layer "F.Fab")
		)
		(pad "1" smd rect
			(at 0 0 270)
			(size 0.508 0.508)
			(layers "F.Cu" "F.Mask" "F.Paste")
			(net "P3V3_STBY")
		)
		(pad "2" smd rect
			(at 0 0.889 270)
			(size 0.508 0.508)
			(layers "F.Cu" "F.Mask" "F.Paste")
			(net "FM_OC_DETECT_EN_N")
		)
		(zone
			(layer "F.Cu")
			(hatch none 0.5)
			(connect_pads
				(clearance 0)
			)
			(min_thickness 0.25)
			(keepout
				(tracks not_allowed)
				(vias allowed)
				(pads allowed)
				(copperpour not_allowed)
				(footprints allowed)
			)
			(placement
				(enabled no)
				(sheetname "")
			)
			(fill
				(thermal_gap 0.5)
				(thermal_bridge_width 0.5)
				(island_removal_mode 0)
			)
			(polygon
				(pts
					(xy 25.273 -76.073) (xy 25.273 -75.565) (xy 25.654 -75.565) (xy 25.654 -76.073)
				)
			)
		)
		(zone
			(layer "F.Cu")
			(hatch none 0.5)
			(connect_pads
				(clearance 0)
			)
			(min_thickness 0.25)
			(keepout
				(tracks allowed)
				(vias not_allowed)
				(pads allowed)
				(copperpour not_allowed)
				(footprints allowed)
			)
			(placement
				(enabled no)
				(sheetname "")
			)
			(fill
				(thermal_gap 0.5)
				(thermal_bridge_width 0.5)
				(island_removal_mode 0)
			)
			(polygon
				(pts
					(xy 25.654 -76.073) (xy 25.654 -75.565) (xy 25.273 -75.565) (xy 25.273 -76.073)
				)
			)
		)
	)
	(footprint ""
		(layer "F.Cu")
		(at 14.478 -86.741 180)
		(property "Reference" "R1D6"
			(at 0 0 180)
			(layer "F.SilkS")
			(hide yes)
			(effects
				(font
					(size 1.27 1.27)
				)
			)
		)
		(property "Value" ""
			(at 0 0 180)
			(layer "F.Fab")
			(effects
				(font
					(size 1.27 1.27)
				)
			)
		)
		(duplicate_pad_numbers_are_jumpers no)
		(fp_rect
			(start 0.2794 -0.1016)
			(end -0.2794 0.9906)
			(stroke
				(width 0)
				(type default)
			)
			(fill no)
			(layer "F.CrtYd")
		)
		(fp_line
			(start 0.2794 0.9906)
			(end 0.2794 -0.1016)
			(stroke
				(width 0.1)
				(type default)
			)
			(layer "F.Fab")
		)
		(fp_line
			(start 0.2794 -0.1016)
			(end -0.2794 -0.1016)
			(stroke
				(width 0.1)
				(type default)
			)
			(layer "F.Fab")
		)
		(fp_line
			(start -0.2794 0.9906)
			(end 0.2794 0.9906)
			(stroke
				(width 0.1)
				(type default)
			)
			(layer "F.Fab")
		)
		(fp_line
			(start -0.2794 -0.1016)
			(end -0.2794 0.9906)
			(stroke
				(width 0.1)
				(type default)
			)
			(layer "F.Fab")
		)
		(pad "1" smd rect
			(at 0 0 180)
			(size 0.508 0.508)
			(layers "F.Cu" "F.Mask" "F.Paste")
			(net "P3V3_STBY")
		)
		(pad "2" smd rect
			(at 0 0.889 180)
			(size 0.508 0.508)
			(layers "F.Cu" "F.Mask" "F.Paste")
			(net "IRQ_PVCCIN_CPU1_VRHOT_LVC3_R_N")
		)
		(zone
			(layer "F.Cu")
			(hatch none 0.5)
			(connect_pads
				(clearance 0)
			)
			(min_thickness 0.25)
			(keepout
				(tracks allowed)
				(vias not_allowed)
				(pads allowed)
				(copperpour not_allowed)
				(footprints allowed)
			)
			(placement
				(enabled no)
				(sheetname "")
			)
			(fill
				(thermal_gap 0.5)
				(thermal_bridge_width 0.5)
				(island_removal_mode 0)
			)
			(polygon
				(pts
					(xy 14.224 -86.995) (xy 14.732 -86.995) (xy 14.732 -87.376) (xy 14.224 -87.376)
				)
			)
		)
		(zone
			(layer "F.Cu")
			(hatch none 0.5)
			(connect_pads
				(clearance 0)
			)
			(min_thickness 0.25)
			(keepout
				(tracks not_allowed)
				(vias allowed)
				(pads allowed)
				(copperpour not_allowed)
				(footprints allowed)
			)
			(placement
				(enabled no)
				(sheetname "")
			)
			(fill
				(thermal_gap 0.5)
				(thermal_bridge_width 0.5)
				(island_removal_mode 0)
			)
			(polygon
				(pts
					(xy 14.224 -86.995) (xy 14.732 -86.995) (xy 14.732 -87.376) (xy 14.224 -87.376)
				)
			)
		)
	)
	(footprint ""
		(layer "F.Cu")
		(at 478.540572 -12.462256)
		(property "Reference" "R9G24"
			(at -0.8382 -0.67818 0)
			(unlocked yes)
			(layer "F.SilkS")
			(effects
				(font
					(size 0.4064 0.254)
					(thickness 0.1524)
				)
				(justify left)
			)
		)
		(property "Value" ""
			(at 0 0 0)
			(layer "F.Fab")
			(effects
				(font
					(size 1.27 1.27)
				)
			)
		)
		(duplicate_pad_numbers_are_jumpers no)
		(fp_poly
			(pts
				(xy -0.2794 -0.1016) (xy 0.2794 -0.1016) (xy 0.2794 0.9906) (xy -0.2794 0.9906)
			)
			(stroke
				(width 0)
				(type default)
			)
			(fill no)
			(layer "F.CrtYd")
		)
		(fp_line
			(start -0.2794 -0.1016)
			(end -0.2794 0.9906)
			(stroke
				(width 0.1)
				(type default)
			)
			(layer "F.Fab")
		)
		(fp_line
			(start -0.2794 0.9906)
			(end 0.2794 0.9906)
			(stroke
				(width 0.1)
				(type default)
			)
			(layer "F.Fab")
		)
		(fp_line
			(start 0.2794 -0.1016)
			(end -0.2794 -0.1016)
			(stroke
				(width 0.1)
				(type default)
			)
			(layer "F.Fab")
		)
		(fp_line
			(start 0.2794 0.9906)
			(end 0.2794 -0.1016)
			(stroke
				(width 0.1)
				(type default)
			)
			(layer "F.Fab")
		)
		(pad "1" smd rect
			(at 0 0)
			(size 0.508 0.508)
			(layers "F.Cu" "F.Mask" "F.Paste")
			(net "NIC_MDI_SPRV_RJ45_0_DP")
		)
		(pad "2" smd rect
			(at 0 0.889)
			(size 0.508 0.508)
			(layers "F.Cu" "F.Mask" "F.Paste")
			(net "NIC_MDI_SPRV_RJ45_0_R_DP")
		)
		(zone
			(layer "F.Cu")
			(hatch none 0.5)
			(connect_pads
				(clearance 0)
			)
			(min_thickness 0.25)
			(keepout
				(tracks allowed)
				(vias not_allowed)
				(pads allowed)
				(copperpour not_allowed)
				(footprints allowed)
			)
			(placement
				(enabled no)
				(sheetname "")
			)
			(fill
				(thermal_gap 0.5)
				(thermal_bridge_width 0.5)
				(island_removal_mode 0)
			)
			(polygon
				(pts
					(xy 478.286572 -12.208256) (xy 478.794572 -12.208256) (xy 478.794572 -11.827256) (xy 478.286572 -11.827256)
				)
			)
		)
		(zone
			(layer "F.Cu")
			(hatch none 0.5)
			(connect_pads
				(clearance 0)
			)
			(min_thickness 0.25)
			(keepout
				(tracks not_allowed)
				(vias allowed)
				(pads allowed)
				(copperpour not_allowed)
				(footprints allowed)
			)
			(placement
				(enabled no)
				(sheetname "")
			)
			(fill
				(thermal_gap 0.5)
				(thermal_bridge_width 0.5)
				(island_removal_mode 0)
			)
			(polygon
				(pts
					(xy 478.286572 -11.827256) (xy 478.794572 -11.827256) (xy 478.794572 -12.208256) (xy 478.286572 -12.208256)
				)
			)
		)
	)
)
